(kicad_pcb
	(version 20260206)
	(generator "pcbnew")
	(generator_version "10.0")
	(general
		(thickness 1.6)
		(legacy_teardrops no)
	)
	(paper "A4")
	(title_block
		(title "peb — Lightning_PEB_BRD.brd")
		(comment 1 "Lightning (Wiwynn / Facebook NVMe JBOF) / footprints 2450-2457 of 2563")
	)
	(layers
		(0 "F.Cu" signal "TOP")
		(4 "In1.Cu" signal "L2GND")
		(6 "In2.Cu" signal "L3")
		(8 "In3.Cu" signal "L4VCC")
		(10 "In4.Cu" signal "L5VCC")
		(12 "In5.Cu" signal "L6")
		(14 "In6.Cu" signal "L7GND")
		(2 "B.Cu" signal "BOTTOM")
		(9 "F.Adhes" user "F.Adhesive")
		(11 "B.Adhes" user "B.Adhesive")
		(13 "F.Paste" user "Package Geometry/Pastemask Top")
		(15 "B.Paste" user "Package Geometry/Pastemask Bottom")
		(5 "F.SilkS" user "Ref Des/Silkscreen Top")
		(7 "B.SilkS" user "Ref Des/Silkscreen Bottom")
		(1 "F.Mask" user "Board Geometry/Soldermask Top")
		(3 "B.Mask" user "Board Geometry/Soldermask Bottom")
		(17 "Dwgs.User" user "User.Drawings")
		(19 "Cmts.User" user "User.Comments")
		(21 "Eco1.User" user "User.Eco1")
		(23 "Eco2.User" user "User.Eco2")
		(25 "Edge.Cuts" user "Board Geometry/Outline")
		(27 "Margin" user)
		(31 "F.CrtYd" user "Package Geometry/Place Bound Top")
		(29 "B.CrtYd" user "Package Geometry/Place Bound Bottom")
		(35 "F.Fab" user "Ref Des/Assembly Top")
		(33 "B.Fab" user "Ref Des/Assembly Bottom")
	)
	(footprint ""
		(layer "B.Cu")
		(at 217.654124 -190.601092 180)
		(property "Reference" "R555"
			(at 0 0 0)
			(layer "B.SilkS")
			(hide yes)
			(effects
				(font
					(size 1.27 1.27)
				)
				(justify mirror)
			)
		)
		(property "Value" "10KR2F-2-GP"
			(at -0.064008 -3.993896 180)
			(unlocked yes)
			(layer "B.Fab")
			(hide yes)
			(effects
				(font
					(size 1.016 1.016)
					(thickness 0.1524)
				)
				(justify mirror)
			)
		)
		(property "Device Type" "R402H16"
			(at -0.064008 -5.517896 180)
			(unlocked yes)
			(layer "B.Fab")
			(hide yes)
			(effects
				(font
					(size 1.016 1.016)
					(thickness 0.1524)
				)
				(justify mirror)
			)
		)
		(duplicate_pad_numbers_are_jumpers no)
		(fp_line
			(start 0.508 -0.9398)
			(end 0.508 0.9398)
			(stroke
				(width 0.1524)
				(type default)
			)
			(layer "B.SilkS")
		)
		(fp_line
			(start -0.508 -0.9398)
			(end 0.508 -0.9398)
			(stroke
				(width 0.1524)
				(type default)
			)
			(layer "B.SilkS")
		)
		(fp_rect
			(start 0.508 0.9398)
			(end -0.508 -0.9398)
			(stroke
				(width 0)
				(type default)
			)
			(fill no)
			(layer "B.CrtYd")
		)
		(fp_rect
			(start 0.508 0.9398)
			(end -0.508 -0.9398)
			(stroke
				(width 0)
				(type default)
			)
			(fill no)
			(layer "B.Fab")
		)
		(pad "1" smd custom
			(at 0 -0.4445)
			(size 0.1397 0.1397)
			(layers "B.Cu" "B.Mask" "B.Paste")
			(net "P3V3_STBY")
			(options
				(clearance outline)
				(anchor circle)
			)
			(primitives
				(gr_poly
					(pts
						(arc
							(start -0.1778 0.2794)
							(mid -0.249642 0.249642)
							(end -0.2794 0.1778)
						)
						(arc
							(start -0.2794 -0.1778)
							(mid -0.249642 -0.249642)
							(end -0.1778 -0.2794)
						)
						(arc
							(start 0.1778 -0.2794)
							(mid 0.249642 -0.249642)
							(end 0.2794 -0.1778)
						)
						(arc
							(start 0.2794 0.1778)
							(mid 0.249642 0.249642)
							(end 0.1778 0.2794)
						)
					)
					(width 0)
					(fill yes)
				)
			)
		)
		(pad "2" smd custom
			(at 0 0.4445)
			(size 0.1397 0.1397)
			(layers "B.Cu" "B.Mask" "B.Paste")
			(net "IOEXP3_AD1")
			(options
				(clearance outline)
				(anchor circle)
			)
			(primitives
				(gr_poly
					(pts
						(arc
							(start -0.1778 0.2794)
							(mid -0.249642 0.249642)
							(end -0.2794 0.1778)
						)
						(arc
							(start -0.2794 -0.1778)
							(mid -0.249642 -0.249642)
							(end -0.1778 -0.2794)
						)
						(arc
							(start 0.1778 -0.2794)
							(mid 0.249642 -0.249642)
							(end 0.2794 -0.1778)
						)
						(arc
							(start 0.2794 0.1778)
							(mid 0.249642 0.249642)
							(end 0.1778 0.2794)
						)
					)
					(width 0)
					(fill yes)
				)
			)
		)
	)
	(footprint ""
		(layer "B.Cu")
		(at 182.14086 -6.47446 -90)
		(property "Reference" "R2936"
			(at 0 0 90)
			(layer "B.SilkS")
			(hide yes)
			(effects
				(font
					(size 1.27 1.27)
				)
				(justify mirror)
			)
		)
		(property "Value" "0R2J-2-GP"
			(at -0.064008 -3.993896 270)
			(unlocked yes)
			(layer "B.Fab")
			(hide yes)
			(effects
				(font
					(size 1.016 1.016)
					(thickness 0.1524)
				)
				(justify mirror)
			)
		)
		(property "Device Type" "R402H16"
			(at -0.064008 -5.517896 270)
			(unlocked yes)
			(layer "B.Fab")
			(hide yes)
			(effects
				(font
					(size 1.016 1.016)
					(thickness 0.1524)
				)
				(justify mirror)
			)
		)
		(duplicate_pad_numbers_are_jumpers no)
		(fp_line
			(start -0.508 -0.9398)
			(end 0.508 -0.9398)
			(stroke
				(width 0.1524)
				(type default)
			)
			(layer "B.SilkS")
		)
		(fp_line
			(start 0.508 -0.9398)
			(end 0.508 0.9398)
			(stroke
				(width 0.1524)
				(type default)
			)
			(layer "B.SilkS")
		)
		(fp_rect
			(start 0.508 0.9398)
			(end -0.508 -0.9398)
			(stroke
				(width 0)
				(type default)
			)
			(fill no)
			(layer "B.CrtYd")
		)
		(fp_rect
			(start 0.508 0.9398)
			(end -0.508 -0.9398)
			(stroke
				(width 0)
				(type default)
			)
			(fill no)
			(layer "B.Fab")
		)
		(pad "1" smd custom
			(at 0 -0.4445 90)
			(size 0.1397 0.1397)
			(layers "B.Cu" "B.Mask" "B.Paste")
			(net "PCIE_REFCLK_H2_P")
			(options
				(clearance outline)
				(anchor circle)
			)
			(primitives
				(gr_poly
					(pts
						(arc
							(start -0.1778 0.2794)
							(mid -0.249642 0.249642)
							(end -0.2794 0.1778)
						)
						(arc
							(start -0.2794 -0.1778)
							(mid -0.249642 -0.249642)
							(end -0.1778 -0.2794)
						)
						(arc
							(start 0.1778 -0.2794)
							(mid 0.249642 -0.249642)
							(end 0.2794 -0.1778)
						)
						(arc
							(start 0.2794 0.1778)
							(mid 0.249642 0.249642)
							(end 0.1778 0.2794)
						)
					)
					(width 0)
					(fill yes)
				)
			)
		)
		(pad "2" smd custom
			(at 0 0.4445 90)
			(size 0.1397 0.1397)
			(layers "B.Cu" "B.Mask" "B.Paste")
			(net "PCIE_REFCLK_H2_P_R")
			(options
				(clearance outline)
				(anchor circle)
			)
			(primitives
				(gr_poly
					(pts
						(arc
							(start -0.1778 0.2794)
							(mid -0.249642 0.249642)
							(end -0.2794 0.1778)
						)
						(arc
							(start -0.2794 -0.1778)
							(mid -0.249642 -0.249642)
							(end -0.1778 -0.2794)
						)
						(arc
							(start 0.1778 -0.2794)
							(mid 0.249642 -0.249642)
							(end 0.2794 -0.1778)
						)
						(arc
							(start 0.2794 0.1778)
							(mid 0.249642 0.249642)
							(end 0.1778 0.2794)
						)
					)
					(width 0)
					(fill yes)
				)
			)
		)
	)
	(footprint ""
		(layer "B.Cu")
		(at 122.428 -205.74)
		(property "Reference" "R3223"
			(at 0 0 0)
			(layer "B.SilkS")
			(hide yes)
			(effects
				(font
					(size 1.27 1.27)
				)
				(justify mirror)
			)
		)
		(property "Value" "0R2J-2-GP"
			(at -0.064008 -3.993896 0)
			(unlocked yes)
			(layer "B.Fab")
			(hide yes)
			(effects
				(font
					(size 1.016 1.016)
					(thickness 0.1524)
				)
				(justify mirror)
			)
		)
		(property "Device Type" "R402H16"
			(at -0.064008 -5.517896 0)
			(unlocked yes)
			(layer "B.Fab")
			(hide yes)
			(effects
				(font
					(size 1.016 1.016)
					(thickness 0.1524)
				)
				(justify mirror)
			)
		)
		(duplicate_pad_numbers_are_jumpers no)
		(fp_line
			(start -0.508 -0.9398)
			(end 0.508 -0.9398)
			(stroke
				(width 0.1524)
				(type default)
			)
			(layer "B.SilkS")
		)
		(fp_line
			(start 0.508 -0.9398)
			(end 0.508 0.9398)
			(stroke
				(width 0.1524)
				(type default)
			)
			(layer "B.SilkS")
		)
		(fp_rect
			(start 0.508 0.9398)
			(end -0.508 -0.9398)
			(stroke
				(width 0)
				(type default)
			)
			(fill no)
			(layer "B.CrtYd")
		)
		(fp_rect
			(start 0.508 0.9398)
			(end -0.508 -0.9398)
			(stroke
				(width 0)
				(type default)
			)
			(fill no)
			(layer "B.Fab")
		)
		(pad "1" smd custom
			(at 0 -0.4445 180)
			(size 0.1397 0.1397)
			(layers "B.Cu" "B.Mask" "B.Paste")
			(net "BMC_SSD_RST#7")
			(options
				(clearance outline)
				(anchor circle)
			)
			(primitives
				(gr_poly
					(pts
						(arc
							(start -0.1778 0.2794)
							(mid -0.249642 0.249642)
							(end -0.2794 0.1778)
						)
						(arc
							(start -0.2794 -0.1778)
							(mid -0.249642 -0.249642)
							(end -0.1778 -0.2794)
						)
						(arc
							(start 0.1778 -0.2794)
							(mid 0.249642 -0.249642)
							(end 0.2794 -0.1778)
						)
						(arc
							(start 0.2794 0.1778)
							(mid 0.249642 0.249642)
							(end 0.1778 0.2794)
						)
					)
					(width 0)
					(fill yes)
				)
			)
		)
		(pad "2" smd custom
			(at 0 0.4445 180)
			(size 0.1397 0.1397)
			(layers "B.Cu" "B.Mask" "B.Paste")
			(net "BMC_SSD_RST#0_A7")
			(options
				(clearance outline)
				(anchor circle)
			)
			(primitives
				(gr_poly
					(pts
						(arc
							(start -0.1778 0.2794)
							(mid -0.249642 0.249642)
							(end -0.2794 0.1778)
						)
						(arc
							(start -0.2794 -0.1778)
							(mid -0.249642 -0.249642)
							(end -0.1778 -0.2794)
						)
						(arc
							(start 0.1778 -0.2794)
							(mid 0.249642 -0.249642)
							(end 0.2794 -0.1778)
						)
						(arc
							(start 0.2794 0.1778)
							(mid 0.249642 0.249642)
							(end 0.1778 0.2794)
						)
					)
					(width 0)
					(fill yes)
				)
			)
		)
	)
	(footprint ""
		(layer "B.Cu")
		(at 237.5408 -32.9946 -90)
		(property "Reference" "C467"
			(at 0 0 90)
			(layer "B.SilkS")
			(hide yes)
			(effects
				(font
					(size 1.27 1.27)
				)
				(justify mirror)
			)
		)
		(property "Value" "SCD1U16V1KX-1-GP"
			(at 2.8321 -1.7399 270)
			(unlocked yes)
			(layer "B.Fab")
			(hide yes)
			(effects
				(font
					(size 1.016 1.016)
					(thickness 0.1524)
				)
				(justify mirror)
			)
		)
		(property "Device Type" "C0201H13"
			(at 2.8321 -3.2639 270)
			(unlocked yes)
			(layer "B.Fab")
			(hide yes)
			(effects
				(font
					(size 1.016 1.016)
					(thickness 0.1524)
				)
				(justify mirror)
			)
		)
		(duplicate_pad_numbers_are_jumpers no)
		(fp_rect
			(start 0.2794 0.6477)
			(end -0.2794 -0.6477)
			(stroke
				(width 0)
				(type default)
			)
			(fill no)
			(layer "B.CrtYd")
		)
		(fp_rect
			(start 0.2794 0.6477)
			(end -0.2794 -0.6477)
			(stroke
				(width 0)
				(type default)
			)
			(fill no)
			(layer "B.Fab")
		)
		(pad "1" smd custom
			(at 0 -0.2794 90)
			(size 0.0762 0.0762)
			(layers "B.Cu" "B.Mask" "B.Paste")
			(net "DUT_VDDO_REF")
			(options
				(clearance outline)
				(anchor circle)
			)
			(primitives
				(gr_poly
					(pts
						(arc
							(start 0.1524 0.127)
							(mid 0.137521 0.162921)
							(end 0.1016 0.1778)
						)
						(arc
							(start -0.1016 0.1778)
							(mid -0.137521 0.162921)
							(end -0.1524 0.127)
						)
						(arc
							(start -0.1524 -0.127)
							(mid -0.137521 -0.162921)
							(end -0.1016 -0.1778)
						)
						(arc
							(start 0.1016 -0.1778)
							(mid 0.137521 -0.162921)
							(end 0.1524 -0.127)
						)
					)
					(width 0)
					(fill yes)
				)
			)
		)
		(pad "2" smd custom
			(at 0 0.2794 90)
			(size 0.0762 0.0762)
			(layers "B.Cu" "B.Mask" "B.Paste")
			(net "GND")
			(options
				(clearance outline)
				(anchor circle)
			)
			(primitives
				(gr_poly
					(pts
						(arc
							(start 0.1524 0.127)
							(mid 0.137521 0.162921)
							(end 0.1016 0.1778)
						)
						(arc
							(start -0.1016 0.1778)
							(mid -0.137521 0.162921)
							(end -0.1524 0.127)
						)
						(arc
							(start -0.1524 -0.127)
							(mid -0.137521 -0.162921)
							(end -0.1016 -0.1778)
						)
						(arc
							(start 0.1016 -0.1778)
							(mid 0.137521 -0.162921)
							(end 0.1524 -0.127)
						)
					)
					(width 0)
					(fill yes)
				)
			)
		)
	)
	(footprint ""
		(layer "B.Cu")
		(at 151.527002 -65.178432 90)
		(property "Reference" "PC195"
			(at 0 0 90)
			(layer "B.SilkS")
			(hide yes)
			(effects
				(font
					(size 1.27 1.27)
				)
				(justify mirror)
			)
		)
		(property "Value" "SC10U25V5KX-GP"
			(at 0.0762 -6.1214 90)
			(unlocked yes)
			(layer "B.Fab")
			(hide yes)
			(effects
				(font
					(size 1.016 1.016)
					(thickness 0.1524)
				)
				(justify mirror)
			)
		)
		(property "Device Type" "C805H56"
			(at 0.0762 -8.1534 90)
			(unlocked yes)
			(layer "B.Fab")
			(hide yes)
			(effects
				(font
					(size 1.016 1.016)
					(thickness 0.1524)
				)
				(justify mirror)
			)
		)
		(duplicate_pad_numbers_are_jumpers no)
		(fp_line
			(start -0.635 0)
			(end 0.635 0)
			(stroke
				(width 0.508)
				(type default)
			)
			(layer "B.SilkS")
		)
		(fp_rect
			(start 0.9652 1.778)
			(end -0.9652 -1.778)
			(stroke
				(width 0)
				(type default)
			)
			(fill no)
			(layer "B.CrtYd")
		)
		(fp_poly
			(pts
				(xy 0.9652 -1.778) (xy -0.9652 -1.778) (xy -0.9652 1.778) (xy 0.9652 1.778)
			)
			(stroke
				(width 0)
				(type default)
			)
			(fill no)
			(layer "B.Fab")
		)
		(pad "1" smd rect
			(at 0 -0.9652 270)
			(size 1.397 1.143)
			(layers "B.Cu" "B.Mask" "B.Paste")
			(net "P0V9_VIN")
		)
		(pad "2" smd rect
			(at 0 0.9652 270)
			(size 1.397 1.143)
			(layers "B.Cu" "B.Mask" "B.Paste")
			(net "GND")
		)
	)
	(footprint ""
		(layer "B.Cu")
		(at 235.1024 -54.0004 -90)
		(property "Reference" "C29"
			(at 0 0 90)
			(layer "B.SilkS")
			(hide yes)
			(effects
				(font
					(size 1.27 1.27)
				)
				(justify mirror)
			)
		)
		(property "Value" "SCD1U16V1KX-1-GP"
			(at 2.8321 -1.7399 270)
			(unlocked yes)
			(layer "B.Fab")
			(hide yes)
			(effects
				(font
					(size 1.016 1.016)
					(thickness 0.1524)
				)
				(justify mirror)
			)
		)
		(property "Device Type" "C0201H13"
			(at 2.8321 -3.2639 270)
			(unlocked yes)
			(layer "B.Fab")
			(hide yes)
			(effects
				(font
					(size 1.016 1.016)
					(thickness 0.1524)
				)
				(justify mirror)
			)
		)
		(duplicate_pad_numbers_are_jumpers no)
		(fp_rect
			(start 0.2794 0.6477)
			(end -0.2794 -0.6477)
			(stroke
				(width 0)
				(type default)
			)
			(fill no)
			(layer "B.CrtYd")
		)
		(fp_rect
			(start 0.2794 0.6477)
			(end -0.2794 -0.6477)
			(stroke
				(width 0)
				(type default)
			)
			(fill no)
			(layer "B.Fab")
		)
		(pad "1" smd custom
			(at 0 -0.2794 90)
			(size 0.0762 0.0762)
			(layers "B.Cu" "B.Mask" "B.Paste")
			(net "DUT_VDD")
			(options
				(clearance outline)
				(anchor circle)
			)
			(primitives
				(gr_poly
					(pts
						(arc
							(start 0.1524 0.127)
							(mid 0.137521 0.162921)
							(end 0.1016 0.1778)
						)
						(arc
							(start -0.1016 0.1778)
							(mid -0.137521 0.162921)
							(end -0.1524 0.127)
						)
						(arc
							(start -0.1524 -0.127)
							(mid -0.137521 -0.162921)
							(end -0.1016 -0.1778)
						)
						(arc
							(start 0.1016 -0.1778)
							(mid 0.137521 -0.162921)
							(end 0.1524 -0.127)
						)
					)
					(width 0)
					(fill yes)
				)
			)
		)
		(pad "2" smd custom
			(at 0 0.2794 90)
			(size 0.0762 0.0762)
			(layers "B.Cu" "B.Mask" "B.Paste")
			(net "GND")
			(options
				(clearance outline)
				(anchor circle)
			)
			(primitives
				(gr_poly
					(pts
						(arc
							(start 0.1524 0.127)
							(mid 0.137521 0.162921)
							(end 0.1016 0.1778)
						)
						(arc
							(start -0.1016 0.1778)
							(mid -0.137521 0.162921)
							(end -0.1524 0.127)
						)
						(arc
							(start -0.1524 -0.127)
							(mid -0.137521 -0.162921)
							(end -0.1016 -0.1778)
						)
						(arc
							(start 0.1016 -0.1778)
							(mid 0.137521 -0.162921)
							(end 0.1524 -0.127)
						)
					)
					(width 0)
					(fill yes)
				)
			)
		)
	)
	(footprint ""
		(layer "B.Cu")
		(at 37.32784 -126.95682 180)
		(property "Reference" "C218"
			(at 0 0 0)
			(layer "B.SilkS")
			(hide yes)
			(effects
				(font
					(size 1.27 1.27)
				)
				(justify mirror)
			)
		)
		(property "Value" "SC1U10V2KX-4-GP"
			(at -1.1811 -2.7051 180)
			(unlocked yes)
			(layer "B.Fab")
			(hide yes)
			(effects
				(font
					(size 1.016 1.016)
					(thickness 0.1524)
				)
				(justify mirror)
			)
		)
		(property "Device Type" "C402H22"
			(at -1.1811 -4.2291 180)
			(unlocked yes)
			(layer "B.Fab")
			(hide yes)
			(effects
				(font
					(size 1.016 1.016)
					(thickness 0.1524)
				)
				(justify mirror)
			)
		)
		(duplicate_pad_numbers_are_jumpers no)
		(fp_rect
			(start 0.4318 0.9525)
			(end -0.4318 -0.9525)
			(stroke
				(width 0)
				(type default)
			)
			(fill no)
			(layer "B.CrtYd")
		)
		(fp_rect
			(start 0.4318 0.9525)
			(end -0.4318 -0.9525)
			(stroke
				(width 0)
				(type default)
			)
			(fill no)
			(layer "B.Fab")
		)
		(pad "1" smd custom
			(at 0 -0.4445)
			(size 0.1524 0.1524)
			(layers "B.Cu" "B.Mask" "B.Paste")
			(net "P3V3_STBY")
			(options
				(clearance outline)
				(anchor circle)
			)
			(primitives
				(gr_poly
					(pts
						(arc
							(start 0.3048 0.2032)
							(mid 0.275042 0.275042)
							(end 0.2032 0.3048)
						)
						(arc
							(start -0.2032 0.3048)
							(mid -0.275042 0.275042)
							(end -0.3048 0.2032)
						)
						(arc
							(start -0.3048 -0.2032)
							(mid -0.275042 -0.275042)
							(end -0.2032 -0.3048)
						)
						(arc
							(start 0.2032 -0.3048)
							(mid 0.275042 -0.275042)
							(end 0.3048 -0.2032)
						)
					)
					(width 0)
					(fill yes)
				)
			)
		)
		(pad "2" smd custom
			(at 0 0.4445)
			(size 0.1524 0.1524)
			(layers "B.Cu" "B.Mask" "B.Paste")
			(net "GND")
			(options
				(clearance outline)
				(anchor circle)
			)
			(primitives
				(gr_poly
					(pts
						(arc
							(start 0.3048 0.2032)
							(mid 0.275042 0.275042)
							(end 0.2032 0.3048)
						)
						(arc
							(start -0.2032 0.3048)
							(mid -0.275042 0.275042)
							(end -0.3048 0.2032)
						)
						(arc
							(start -0.3048 -0.2032)
							(mid -0.275042 -0.275042)
							(end -0.2032 -0.3048)
						)
						(arc
							(start 0.2032 -0.3048)
							(mid 0.275042 -0.275042)
							(end 0.3048 -0.2032)
						)
					)
					(width 0)
					(fill yes)
				)
			)
		)
	)
	(footprint ""
		(layer "B.Cu")
		(at 318.135 -68.58 180)
		(property "Reference" "PC181"
			(at 0 0 0)
			(layer "B.SilkS")
			(hide yes)
			(effects
				(font
					(size 1.27 1.27)
				)
				(justify mirror)
			)
		)
		(property "Value" "SC22U6D3V5MX-5-GP"
			(at 0.0762 -6.1214 180)
			(unlocked yes)
			(layer "B.Fab")
			(hide yes)
			(effects
				(font
					(size 1.016 1.016)
					(thickness 0.1524)
				)
				(justify mirror)
			)
		)
		(property "Device Type" "C805H56"
			(at 0.0762 -8.1534 180)
			(unlocked yes)
			(layer "B.Fab")
			(hide yes)
			(effects
				(font
					(size 1.016 1.016)
					(thickness 0.1524)
				)
				(justify mirror)
			)
		)
		(duplicate_pad_numbers_are_jumpers no)
		(fp_line
			(start -0.635 0)
			(end 0.635 0)
			(stroke
				(width 0.508)
				(type default)
			)
			(layer "B.SilkS")
		)
		(fp_rect
			(start 0.9652 1.778)
			(end -0.9652 -1.778)
			(stroke
				(width 0)
				(type default)
			)
			(fill no)
			(layer "B.CrtYd")
		)
		(fp_poly
			(pts
				(xy 0.9652 -1.778) (xy -0.9652 -1.778) (xy -0.9652 1.778) (xy 0.9652 1.778)
			)
			(stroke
				(width 0)
				(type default)
			)
			(fill no)
			(layer "B.Fab")
		)
		(pad "1" smd rect
			(at 0 -0.9652)
			(size 1.397 1.143)
			(layers "B.Cu" "B.Mask" "B.Paste")
			(net "P0V9_E")
		)
		(pad "2" smd rect
			(at 0 0.9652)
			(size 1.397 1.143)
			(layers "B.Cu" "B.Mask" "B.Paste")
			(net "GND")
		)
	)
)
